# T6G (Grand Teton) — schematic netlist excerpt (pin names and nets, part order shuffled) for the footprints in the layout excerpt that follows; sources: Cadence DE-HDL packaged netlist, KiCad conversion of 04192023_DAF0TMB3IC0_F0TG_MB_C_brd_V02_OCP.brd

C2604  Q_CAP  22UF 4V 20% X6S  pkg C0402  page 70 : A = PVDDIO_P0 ; B = GND
C5015  Q_CAP  1000PF 50V 5% EMPTY  pkg 0402  page 190 : A = PWRGD_P3V3_AUX ; B = GND

(kicad_pcb
	(version 20260206)
	(generator "pcbnew")
	(generator_version "10.0")
	(general
		(thickness 1.6)
		(legacy_teardrops no)
	)
	(paper "A4")
	(title_block
		(title "04192023_DAF0TMB3IC0_F0TG_MB_C_brd_V02_OCP.brd")
		(comment 1 "Grand Teton / footprints 6741-6742 of 8354")
	)
	(layers
		(0 "F.Cu" signal "TOP")
		(4 "In1.Cu" signal "GND")
		(6 "In2.Cu" signal "IN1")
		(8 "In3.Cu" signal "GND1")
		(10 "In4.Cu" signal "IN2")
		(12 "In5.Cu" signal "GND2")
		(14 "In6.Cu" signal "IN3")
		(16 "In7.Cu" signal "GND3")
		(18 "In8.Cu" signal "VCC")
		(20 "In9.Cu" signal "VCC1")
		(22 "In10.Cu" signal "GND4")
		(24 "In11.Cu" signal "IN4")
		(26 "In12.Cu" signal "GND5")
		(28 "In13.Cu" signal "IN5")
		(30 "In14.Cu" signal "GND6")
		(32 "In15.Cu" signal "IN6")
		(34 "In16.Cu" signal "GND7")
		(2 "B.Cu" signal "BOTTOM")
		(9 "F.Adhes" user "F.Adhesive")
		(11 "B.Adhes" user "B.Adhesive")
		(13 "F.Paste" user "Package Geometry/Pastemask Top")
		(15 "B.Paste" user "Package Geometry/Pastemask Bottom")
		(5 "F.SilkS" user "Ref Des/Silkscreen Top")
		(7 "B.SilkS" user "Ref Des/Silkscreen Bottom")
		(1 "F.Mask" user "Board Geometry/Soldermask Top")
		(3 "B.Mask" user "Board Geometry/Soldermask Bottom")
		(17 "Dwgs.User" user "User.Drawings")
		(19 "Cmts.User" user "User.Comments")
		(21 "Eco1.User" user "User.Eco1")
		(23 "Eco2.User" user "User.Eco2")
		(25 "Edge.Cuts" user "Board Geometry/Outline")
		(27 "Margin" user)
		(31 "F.CrtYd" user "Package Geometry/Place Bound Top")
		(29 "B.CrtYd" user "Package Geometry/Place Bound Bottom")
		(35 "F.Fab" user "Ref Des/Assembly Top")
		(33 "B.Fab" user "Ref Des/Assembly Bottom")
	)
	(footprint ""
		(layer "B.Cu")
		(at 460.405988 -44.416726)
		(property "Reference" "C5015"
			(at 0 0 0)
			(layer "B.SilkS")
			(hide yes)
			(effects
				(font
					(size 1.27 1.27)
				)
				(justify mirror)
			)
		)
		(property "Value" ""
			(at 0 0 0)
			(layer "B.Fab")
			(effects
				(font
					(size 1.27 1.27)
				)
				(justify mirror)
			)
		)
		(duplicate_pad_numbers_are_jumpers no)
		(fp_line
			(start -0.7874 -0.4064)
			(end -0.7874 0.4064)
			(stroke
				(width 0.1524)
				(type default)
			)
			(layer "B.SilkS")
		)
		(fp_line
			(start -0.7874 0.4064)
			(end 0.7874 0.4064)
			(stroke
				(width 0.1524)
				(type default)
			)
			(layer "B.SilkS")
		)
		(fp_line
			(start 0.7874 -0.4064)
			(end -0.7874 -0.4064)
			(stroke
				(width 0.1524)
				(type default)
			)
			(layer "B.SilkS")
		)
		(fp_line
			(start 0.7874 0.4064)
			(end 0.7874 -0.4064)
			(stroke
				(width 0.1524)
				(type default)
			)
			(layer "B.SilkS")
		)
		(fp_line
			(start -0.67945 -0.3048)
			(end -0.67945 0.3048)
			(stroke
				(width 0.1)
				(type default)
			)
			(layer "B.Fab")
		)
		(fp_line
			(start -0.67945 0.3048)
			(end -0.120396 0.3048)
			(stroke
				(width 0.1)
				(type default)
			)
			(layer "B.Fab")
		)
		(fp_line
			(start -0.12065 -0.3048)
			(end -0.67945 -0.3048)
			(stroke
				(width 0.1)
				(type default)
			)
			(layer "B.Fab")
		)
		(fp_line
			(start -0.12065 -0.2794)
			(end -0.12065 -0.3048)
			(stroke
				(width 0.1)
				(type default)
			)
			(layer "B.Fab")
		)
		(fp_line
			(start -0.120396 0.2794)
			(end 0.12065 0.2794)
			(stroke
				(width 0.1)
				(type default)
			)
			(layer "B.Fab")
		)
		(fp_line
			(start -0.120396 0.3048)
			(end -0.120396 0.2794)
			(stroke
				(width 0.1)
				(type default)
			)
			(layer "B.Fab")
		)
		(fp_line
			(start 0.12065 -0.305054)
			(end 0.12065 -0.2794)
			(stroke
				(width 0.1)
				(type default)
			)
			(layer "B.Fab")
		)
		(fp_line
			(start 0.12065 -0.2794)
			(end -0.12065 -0.2794)
			(stroke
				(width 0.1)
				(type default)
			)
			(layer "B.Fab")
		)
		(fp_line
			(start 0.12065 0.2794)
			(end 0.12065 0.3048)
			(stroke
				(width 0.1)
				(type default)
			)
			(layer "B.Fab")
		)
		(fp_line
			(start 0.12065 0.3048)
			(end 0.67945 0.3048)
			(stroke
				(width 0.1)
				(type default)
			)
			(layer "B.Fab")
		)
		(fp_line
			(start 0.67945 -0.305054)
			(end 0.12065 -0.305054)
			(stroke
				(width 0.1)
				(type default)
			)
			(layer "B.Fab")
		)
		(fp_line
			(start 0.67945 0.3048)
			(end 0.67945 -0.305054)
			(stroke
				(width 0.1)
				(type default)
			)
			(layer "B.Fab")
		)
		(pad "1" smd circle
			(at 0.40005 0 180)
			(size 0 0)
			(layers "B.Cu" "B.Mask" "B.Paste")
			(net "PWRGD_P3V3_AUX")
		)
		(pad "2" smd circle
			(at -0.40005 0 180)
			(size 0 0)
			(layers "B.Cu" "B.Mask" "B.Paste")
			(net "GND")
		)
	)
	(footprint ""
		(layer "B.Cu")
		(at 346.373958 -263.521952)
		(property "Reference" "C2604"
			(at 0 0 0)
			(layer "B.SilkS")
			(hide yes)
			(effects
				(font
					(size 1.27 1.27)
				)
				(justify mirror)
			)
		)
		(property "Value" ""
			(at 0 0 0)
			(layer "B.Fab")
			(effects
				(font
					(size 1.27 1.27)
				)
				(justify mirror)
			)
		)
		(duplicate_pad_numbers_are_jumpers no)
		(fp_line
			(start -0.7874 -0.4064)
			(end -0.7874 0.4064)
			(stroke
				(width 0.1524)
				(type default)
			)
			(layer "B.SilkS")
		)
		(fp_line
			(start -0.7874 0.4064)
			(end 0.7874 0.4064)
			(stroke
				(width 0.1524)
				(type default)
			)
			(layer "B.SilkS")
		)
		(fp_line
			(start 0.7874 -0.4064)
			(end -0.7874 -0.4064)
			(stroke
				(width 0.1524)
				(type default)
			)
			(layer "B.SilkS")
		)
		(fp_line
			(start 0.7874 0.4064)
			(end 0.7874 -0.4064)
			(stroke
				(width 0.1524)
				(type default)
			)
			(layer "B.SilkS")
		)
		(fp_line
			(start -0.67945 -0.3048)
			(end -0.67945 0.3048)
			(stroke
				(width 0.1)
				(type default)
			)
			(layer "B.Fab")
		)
		(fp_line
			(start -0.67945 0.3048)
			(end -0.120396 0.3048)
			(stroke
				(width 0.1)
				(type default)
			)
			(layer "B.Fab")
		)
		(fp_line
			(start -0.12065 -0.3048)
			(end -0.67945 -0.3048)
			(stroke
				(width 0.1)
				(type default)
			)
			(layer "B.Fab")
		)
		(fp_line
			(start -0.12065 -0.2794)
			(end -0.12065 -0.3048)
			(stroke
				(width 0.1)
				(type default)
			)
			(layer "B.Fab")
		)
		(fp_line
			(start -0.120396 0.2794)
			(end 0.12065 0.2794)
			(stroke
				(width 0.1)
				(type default)
			)
			(layer "B.Fab")
		)
		(fp_line
			(start -0.120396 0.3048)
			(end -0.120396 0.2794)
			(stroke
				(width 0.1)
				(type default)
			)
			(layer "B.Fab")
		)
		(fp_line
			(start 0.12065 -0.305054)
			(end 0.12065 -0.2794)
			(stroke
				(width 0.1)
				(type default)
			)
			(layer "B.Fab")
		)
		(fp_line
			(start 0.12065 -0.2794)
			(end -0.12065 -0.2794)
			(stroke
				(width 0.1)
				(type default)
			)
			(layer "B.Fab")
		)
		(fp_line
			(start 0.12065 0.2794)
			(end 0.12065 0.3048)
			(stroke
				(width 0.1)
				(type default)
			)
			(layer "B.Fab")
		)
		(fp_line
			(start 0.12065 0.3048)
			(end 0.67945 0.3048)
			(stroke
				(width 0.1)
				(type default)
			)
			(layer "B.Fab")
		)
		(fp_line
			(start 0.67945 -0.305054)
			(end 0.12065 -0.305054)
			(stroke
				(width 0.1)
				(type default)
			)
			(layer "B.Fab")
		)
		(fp_line
			(start 0.67945 0.3048)
			(end 0.67945 -0.305054)
			(stroke
				(width 0.1)
				(type default)
			)
			(layer "B.Fab")
		)
		(pad "1" smd circle
			(at 0.40005 0 180)
			(size 0 0)
			(layers "B.Cu" "B.Mask" "B.Paste")
			(net "PVDDIO_P0")
		)
		(pad "2" smd circle
			(at -0.40005 0 180)
			(size 0 0)
			(layers "B.Cu" "B.Mask" "B.Paste")
			(net "GND")
		)
	)
)
